(kicad_pcb
	(version 20260206)
	(generator "pcbnew")
	(generator_version "10.0")
	(general
		(thickness 1.6)
		(legacy_teardrops no)
	)
	(paper "A4")
	(title_block
		(title "v1-chassis-manager — T6M_CM_d_v01_1031_1645.brd")
		(comment 1 "Open CloudServer (Microsoft) / footprints 13-18 of 2512")
	)
	(layers
		(0 "F.Cu" signal "TOP")
		(4 "In1.Cu" signal "GND1")
		(6 "In2.Cu" signal "IN1")
		(8 "In3.Cu" signal "VCC1")
		(10 "In4.Cu" signal "VCC2")
		(12 "In5.Cu" signal "GND2")
		(14 "In6.Cu" signal "IN2")
		(16 "In7.Cu" signal "IN3")
		(18 "In8.Cu" signal "GND3")
		(2 "B.Cu" signal "BOTTOM")
		(9 "F.Adhes" user "F.Adhesive")
		(11 "B.Adhes" user "B.Adhesive")
		(13 "F.Paste" user "Package Geometry/Pastemask Top")
		(15 "B.Paste" user "Package Geometry/Pastemask Bottom")
		(5 "F.SilkS" user "Ref Des/Silkscreen Top")
		(7 "B.SilkS" user "Ref Des/Silkscreen Bottom")
		(1 "F.Mask" user "Board Geometry/Soldermask Top")
		(3 "B.Mask" user "Board Geometry/Soldermask Bottom")
		(17 "Dwgs.User" user "User.Drawings")
		(19 "Cmts.User" user "User.Comments")
		(21 "Eco1.User" user "User.Eco1")
		(23 "Eco2.User" user "User.Eco2")
		(25 "Edge.Cuts" user "Board Geometry/Outline")
		(27 "Margin" user)
		(31 "F.CrtYd" user "Package Geometry/Place Bound Top")
		(29 "B.CrtYd" user "Package Geometry/Place Bound Bottom")
		(35 "F.Fab" user "Ref Des/Assembly Top")
		(33 "B.Fab" user "Ref Des/Assembly Bottom")
	)
	(footprint ""
		(layer "F.Cu")
		(at 83.702906 -96.604836)
		(property "Reference" "C841"
			(at 3.238754 2.231136 0)
			(unlocked yes)
			(layer "F.SilkS")
			(effects
				(font
					(size 0.7874 0.5842)
					(thickness 0.1524)
				)
			)
		)
		(property "Value" ""
			(at 0 0 0)
			(layer "F.Fab")
			(effects
				(font
					(size 1.27 1.27)
				)
			)
		)
		(duplicate_pad_numbers_are_jumpers no)
		(fp_line
			(start -1.2954 -0.5842)
			(end 1.2954 -0.5842)
			(stroke
				(width 0.1524)
				(type default)
			)
			(layer "F.SilkS")
		)
		(fp_line
			(start -1.2954 0.5842)
			(end -1.2954 -0.5842)
			(stroke
				(width 0.1524)
				(type default)
			)
			(layer "F.SilkS")
		)
		(fp_line
			(start 0 -0.5842)
			(end 0 0.5842)
			(stroke
				(width 0.1524)
				(type default)
			)
			(layer "F.SilkS")
		)
		(fp_line
			(start 1.2954 -0.5842)
			(end 1.2954 0.5842)
			(stroke
				(width 0.1524)
				(type default)
			)
			(layer "F.SilkS")
		)
		(fp_line
			(start 1.2954 0.5842)
			(end -1.2954 0.5842)
			(stroke
				(width 0.1524)
				(type default)
			)
			(layer "F.SilkS")
		)
		(fp_poly
			(pts
				(xy 0.8636 -0.4572) (xy 0.8636 -0.3556) (xy 1.143 -0.3556) (xy 1.143 0.3556) (xy 0.8636 0.3556)
				(xy 0.8636 0.4572) (xy -0.8636 0.4572) (xy -0.8636 0.3556) (xy -1.143 0.3556) (xy -1.143 -0.3556)
				(xy -0.8636 -0.3556) (xy -0.8636 -0.4572)
			)
			(stroke
				(width 0)
				(type default)
			)
			(fill no)
			(layer "F.CrtYd")
		)
		(fp_line
			(start -0.884936 -0.504952)
			(end 0.884936 -0.504952)
			(stroke
				(width 0.1)
				(type default)
			)
			(layer "F.Fab")
		)
		(fp_line
			(start -0.884936 0.504952)
			(end -0.884936 -0.504952)
			(stroke
				(width 0.1)
				(type default)
			)
			(layer "F.Fab")
		)
		(fp_line
			(start 0.884936 -0.504952)
			(end 0.884936 0.504952)
			(stroke
				(width 0.1)
				(type default)
			)
			(layer "F.Fab")
		)
		(fp_line
			(start 0.884936 0.504952)
			(end -0.884936 0.504952)
			(stroke
				(width 0.1)
				(type default)
			)
			(layer "F.Fab")
		)
		(pad "1" smd rect
			(at 0.7366 0 90)
			(size 0.7112 0.8128)
			(layers "F.Cu" "F.Mask" "F.Paste")
			(net "FM_CPLD_NODE1_P3V3_SUS_EN_LV")
		)
		(pad "2" smd rect
			(at -0.7366 0 90)
			(size 0.7112 0.8128)
			(layers "F.Cu" "F.Mask" "F.Paste")
			(net "P3V3_SUS_NODE1")
		)
	)
	(footprint ""
		(layer "F.Cu")
		(at 88.232488 -155.705302)
		(property "Reference" "PC37"
			(at -1.467104 5.634228 0)
			(unlocked yes)
			(layer "F.SilkS")
			(effects
				(font
					(size 0.7874 0.5842)
					(thickness 0.1524)
				)
				(justify left)
			)
		)
		(property "Value" ""
			(at 0 0 0)
			(layer "F.Fab")
			(effects
				(font
					(size 1.27 1.27)
				)
			)
		)
		(duplicate_pad_numbers_are_jumpers no)
		(fp_line
			(start -1.905 -0.8636)
			(end 1.905 -0.8636)
			(stroke
				(width 0.1524)
				(type default)
			)
			(layer "F.SilkS")
		)
		(fp_line
			(start -1.905 0.8636)
			(end -1.905 -0.8636)
			(stroke
				(width 0.1524)
				(type default)
			)
			(layer "F.SilkS")
		)
		(fp_line
			(start 0 0.8382)
			(end 0 -0.8382)
			(stroke
				(width 0.1524)
				(type default)
			)
			(layer "F.SilkS")
		)
		(fp_line
			(start 1.905 -0.8636)
			(end 1.905 0.8636)
			(stroke
				(width 0.1524)
				(type default)
			)
			(layer "F.SilkS")
		)
		(fp_line
			(start 1.905 0.8636)
			(end -1.905 0.8636)
			(stroke
				(width 0.1524)
				(type default)
			)
			(layer "F.SilkS")
		)
		(fp_rect
			(start -1.524 0.7366)
			(end 1.524 -0.7366)
			(stroke
				(width 0)
				(type default)
			)
			(fill no)
			(layer "F.CrtYd")
		)
		(pad "1" smd rect
			(at 0.94996 0)
			(size 1.1176 1.3716)
			(layers "F.Cu" "F.Mask" "F.Paste")
			(net "P1V8_STB_NODE1")
		)
		(pad "2" smd rect
			(at -0.94996 0)
			(size 1.1176 1.3716)
			(layers "F.Cu" "F.Mask" "F.Paste")
			(net "GND")
		)
	)
	(footprint ""
		(layer "F.Cu")
		(at 26.825702 -37.473128 -90)
		(property "Reference" ""
			(at 0 0 270)
			(layer "F.SilkS")
			(hide yes)
			(effects
				(font
					(size 1.27 1.27)
				)
			)
		)
		(property "Value" ""
			(at 0 0 270)
			(layer "F.Fab")
			(effects
				(font
					(size 1.27 1.27)
				)
			)
		)
		(duplicate_pad_numbers_are_jumpers no)
		(fp_poly
			(pts
				(arc
					(start 0 -1.4986)
					(mid 0 1.4986)
					(end 0 -1.4986)
				)
			)
			(stroke
				(width 0)
				(type default)
			)
			(fill no)
			(layer "F.CrtYd")
		)
		(pad "1" smd circle
			(at 0 0 270)
			(size 0.9906 0.9906)
			(layers "F.Cu" "F.Mask" "F.Paste")
			(net "Net_41")
		)
		(zone
			(layer "F.Cu")
			(hatch none 0.5)
			(connect_pads
				(clearance 0)
			)
			(min_thickness 0.25)
			(keepout
				(tracks not_allowed)
				(vias allowed)
				(pads allowed)
				(copperpour not_allowed)
				(footprints allowed)
			)
			(placement
				(enabled no)
				(sheetname "")
			)
			(fill
				(thermal_gap 0.5)
				(thermal_bridge_width 0.5)
				(island_removal_mode 0)
			)
			(polygon
				(pts
					(arc
						(start 25.200102 -37.473128)
						(mid 28.451302 -37.473128)
						(end 25.200102 -37.473128)
					)
				)
			)
		)
	)
	(footprint ""
		(layer "F.Cu")
		(at 48.192182 -173.527466 180)
		(property "Reference" "U87"
			(at 1.185418 -133.039612 90)
			(unlocked yes)
			(layer "F.SilkS")
			(effects
				(font
					(size 0.7874 0.5842)
					(thickness 0.1524)
				)
				(justify left)
			)
		)
		(property "Value" ""
			(at 0 0 180)
			(layer "F.Fab")
			(effects
				(font
					(size 1.27 1.27)
				)
			)
		)
		(duplicate_pad_numbers_are_jumpers no)
		(fp_line
			(start 1.549908 2.032)
			(end -1.549908 2.032)
			(stroke
				(width 0.1524)
				(type default)
			)
			(layer "F.SilkS")
		)
		(fp_line
			(start 1.549908 -2.032)
			(end 1.549908 2.032)
			(stroke
				(width 0.1524)
				(type default)
			)
			(layer "F.SilkS")
		)
		(fp_line
			(start -1.549908 2.032)
			(end -1.549908 -2.032)
			(stroke
				(width 0.1524)
				(type default)
			)
			(layer "F.SilkS")
		)
		(fp_line
			(start -1.549908 -2.032)
			(end 1.549908 -2.032)
			(stroke
				(width 0.1524)
				(type default)
			)
			(layer "F.SilkS")
		)
		(fp_poly
			(pts
				(xy -2.9464 1.016) (xy -2.9464 1.524) (xy -2.1844 1.27)
			)
			(stroke
				(width 0)
				(type default)
			)
			(fill yes)
			(layer "F.SilkS")
		)
		(fp_poly
			(pts
				(xy -1.549908 0.849884) (xy -1.2319 0.849884) (xy -1.2319 1.9431) (xy -1.1811 1.9431) (xy 1.1811 1.9431)
				(xy 1.2319 1.9431) (xy 1.2319 0.849884) (xy 1.549908 0.849884) (xy 1.549908 -0.849884) (xy 1.2319 -0.849884)
				(xy 1.2319 -1.9431) (xy 1.1811 -1.9431) (xy -1.1811 -1.9431) (xy -1.2319 -1.9431) (xy -1.2319 -0.849884)
				(xy -1.549908 -0.849884)
			)
			(stroke
				(width 0)
				(type default)
			)
			(fill no)
			(layer "F.CrtYd")
		)
		(fp_line
			(start 1.549908 0.849884)
			(end 1.549908 -0.849884)
			(stroke
				(width 0.1)
				(type default)
			)
			(layer "F.Fab")
		)
		(fp_line
			(start 1.549908 -0.849884)
			(end -1.549908 -0.849884)
			(stroke
				(width 0.1)
				(type default)
			)
			(layer "F.Fab")
		)
		(fp_line
			(start -1.549908 0.849884)
			(end 1.549908 0.849884)
			(stroke
				(width 0.1)
				(type default)
			)
			(layer "F.Fab")
		)
		(fp_line
			(start -1.549908 -0.849884)
			(end -1.549908 0.849884)
			(stroke
				(width 0.1)
				(type default)
			)
			(layer "F.Fab")
		)
		(fp_text user "3"
			(at 2.377186 2.550668 0)
			(unlocked yes)
			(layer "F.SilkS")
			(effects
				(font
					(size 0.635 0.4064)
					(thickness 0.1524)
				)
				(justify left)
			)
		)
		(fp_text user "4"
			(at 0.95885 -2.513076 0)
			(unlocked yes)
			(layer "F.SilkS")
			(effects
				(font
					(size 0.635 0.4064)
					(thickness 0.1524)
				)
				(justify left)
			)
		)
		(fp_text user "1"
			(at -1.537462 2.55905 0)
			(unlocked yes)
			(layer "F.SilkS")
			(effects
				(font
					(size 0.635 0.4064)
					(thickness 0.1524)
				)
				(justify left)
			)
		)
		(fp_text user "5"
			(at -1.883156 -2.59334 0)
			(unlocked yes)
			(layer "F.SilkS")
			(effects
				(font
					(size 0.635 0.4064)
					(thickness 0.1524)
				)
				(justify left)
			)
		)
		(pad "1" smd rect
			(at -0.94996 1.225042 180)
			(size 0.4572 1.3208)
			(layers "F.Cu" "F.Mask" "F.Paste")
			(net "Net_1708")
		)
		(pad "2" smd rect
			(at 0 1.225042 180)
			(size 0.4572 1.3208)
			(layers "F.Cu" "F.Mask" "F.Paste")
			(net "PSU6_DC_OK_R_BUF")
		)
		(pad "3" smd rect
			(at 0.94996 1.225042 180)
			(size 0.4572 1.3208)
			(layers "F.Cu" "F.Mask" "F.Paste")
			(net "GND")
		)
		(pad "4" smd rect
			(at 0.94996 -1.225042 180)
			(size 0.4572 1.3208)
			(layers "F.Cu" "F.Mask" "F.Paste")
			(net "PSU6_DC_OK")
		)
		(pad "5" smd rect
			(at -0.94996 -1.225042 180)
			(size 0.4572 1.3208)
			(layers "F.Cu" "F.Mask" "F.Paste")
			(net "P3V3_NODE1")
		)
	)
	(footprint ""
		(layer "F.Cu")
		(at 47.419768 -105.38079)
		(property "Reference" "R1103"
			(at -0.191008 2.048002 0)
			(unlocked yes)
			(layer "F.SilkS")
			(effects
				(font
					(size 0.7874 0.5842)
					(thickness 0.1524)
				)
				(justify left)
			)
		)
		(property "Value" ""
			(at 0 0 0)
			(layer "F.Fab")
			(effects
				(font
					(size 1.27 1.27)
				)
			)
		)
		(duplicate_pad_numbers_are_jumpers no)
		(fp_line
			(start -0.7874 -0.4064)
			(end 0.7874 -0.4064)
			(stroke
				(width 0.1524)
				(type default)
			)
			(layer "F.SilkS")
		)
		(fp_line
			(start -0.7874 0.4064)
			(end -0.7874 -0.4064)
			(stroke
				(width 0.1524)
				(type default)
			)
			(layer "F.SilkS")
		)
		(fp_line
			(start 0.7874 -0.4064)
			(end 0.7874 0.4064)
			(stroke
				(width 0.1524)
				(type default)
			)
			(layer "F.SilkS")
		)
		(fp_line
			(start 0.7874 0.4064)
			(end -0.7874 0.4064)
			(stroke
				(width 0.1524)
				(type default)
			)
			(layer "F.SilkS")
		)
		(fp_poly
			(pts
				(xy -0.508 0.2794) (xy -0.508 0.2286) (xy -0.635 0.2286) (xy -0.635 -0.254) (xy -0.5334 -0.254)
				(xy -0.5334 -0.2794) (xy 0.5334 -0.2794) (xy 0.5334 -0.254) (xy 0.635 -0.254) (xy 0.635 0.254) (xy 0.5334 0.254)
				(xy 0.5334 0.2794)
			)
			(stroke
				(width 0)
				(type default)
			)
			(fill no)
			(layer "F.CrtYd")
		)
		(pad "1" smd rect
			(at 0.40005 0)
			(size 0.4572 0.508)
			(layers "F.Cu" "F.Mask" "F.Paste")
			(net "GND")
		)
		(pad "2" smd rect
			(at -0.40005 0)
			(size 0.4572 0.508)
			(layers "F.Cu" "F.Mask" "F.Paste")
			(net "PWRGD_NODE1_P5V_STB_PG")
		)
	)
	(footprint ""
		(layer "F.Cu")
		(at 116.18976 -185.205624 90)
		(property "Reference" "C754"
			(at 4.768088 0.929132 90)
			(unlocked yes)
			(layer "F.SilkS")
			(effects
				(font
					(size 0.7874 0.5842)
					(thickness 0.1524)
				)
				(justify left)
			)
		)
		(property "Value" ""
			(at 0 0 90)
			(layer "F.Fab")
			(effects
				(font
					(size 1.27 1.27)
				)
			)
		)
		(duplicate_pad_numbers_are_jumpers no)
		(fp_line
			(start 0.7874 -0.4064)
			(end 0.7874 0.4064)
			(stroke
				(width 0.1524)
				(type default)
			)
			(layer "F.SilkS")
		)
		(fp_line
			(start -0.7874 -0.4064)
			(end 0.7874 -0.4064)
			(stroke
				(width 0.1524)
				(type default)
			)
			(layer "F.SilkS")
		)
		(fp_line
			(start 0 0.381)
			(end 0 -0.381)
			(stroke
				(width 0.1524)
				(type default)
			)
			(layer "F.SilkS")
		)
		(fp_line
			(start 0.7874 0.4064)
			(end -0.7874 0.4064)
			(stroke
				(width 0.1524)
				(type default)
			)
			(layer "F.SilkS")
		)
		(fp_line
			(start -0.7874 0.4064)
			(end -0.7874 -0.4064)
			(stroke
				(width 0.1524)
				(type default)
			)
			(layer "F.SilkS")
		)
		(fp_poly
			(pts
				(xy -0.5334 0.254) (xy -0.635 0.254) (xy -0.635 0.2286) (xy -0.635 -0.254) (xy -0.5334 -0.254) (xy -0.5334 -0.2794)
				(xy 0.5334 -0.2794) (xy 0.5334 -0.254) (xy 0.635 -0.254) (xy 0.635 0.254) (xy 0.5334 0.254) (xy 0.5334 0.2794)
				(xy -0.508 0.2794) (xy -0.5334 0.2794)
			)
			(stroke
				(width 0)
				(type default)
			)
			(fill no)
			(layer "F.CrtYd")
		)
		(pad "1" smd rect
			(at 0.40005 0 90)
			(size 0.4572 0.508)
			(layers "F.Cu" "F.Mask" "F.Paste")
			(net "UART_T8_NODE3_RXD")
		)
		(pad "2" smd rect
			(at -0.40005 0 90)
			(size 0.4572 0.508)
			(layers "F.Cu" "F.Mask" "F.Paste")
			(net "GND")
		)
	)
)
